FILE_TYPE = CONNECTIVITY;
{Allegro Design Entry HDL 16.6-p007 (v16-6-112F) 10/10/2012}
"PAGE_NUMBER" = 117;
0"NC";
1"P3E_CPU0_PE1_PCH_R_RXP<15:8>";
2"P3E_CPU0_PE1_PCH_R_RXN<15:8>";
3"DMI_CPU0_PCH_RX_DP<3:0>";
4"DMI_CPU0_PCH_RX_DN<3:0>";
5"P3E_CPU0_PE1_PCH_RXP<7:0>";
6"P3E_CPU0_PE1_PCH_RXN<7:0>";
7"P3E_CPU0_PE1_PCH_C_TXN<15:8>";
8"P3E_CPU0_PE1_PCH_C_TXP<15:8>";
9"DMI_CPU0_PCH_TX_C_DP<3:0>";
10"DMI_CPU0_PCH_TX_C_DN<3:0>";
11"P3E_CPU0_PE1_PCH_TXP<7:0>";
12"P3E_CPU0_PE1_PCH_TXN<7:0>";
13"P3E_CPU0_PE1_PCH_TXN<0>";
14"P3E_CPU0_PE1_PCH_TXP<0>";
15"P3E_CPU0_PE1_PCH_TXN<1>";
16"P3E_CPU0_PE1_PCH_TXP<1>";
17"P3E_CPU0_PE1_PCH_TXN<2>";
18"P3E_CPU0_PE1_PCH_TXP<2>";
19"P3E_CPU0_PE1_PCH_TXN<3>";
20"P3E_CPU0_PE1_PCH_TXP<3>";
21"P3E_CPU0_PE1_PCH_TXN<4>";
22"P3E_CPU0_PE1_PCH_TXP<4>";
23"P3E_CPU0_PE1_PCH_TXN<5>";
24"P3E_CPU0_PE1_PCH_TXP<5>";
25"P3E_CPU0_PE1_PCH_TXN<6>";
26"P3E_CPU0_PE1_PCH_TXP<6>";
27"P3E_CPU0_PE1_PCH_TXN<7>";
28"P3E_CPU0_PE1_PCH_TXP<7>";
29"P3E_CPU0_PE1_PCH_C_TXP<8>";
30"P3E_CPU0_PE1_PCH_C_TXN<8>";
31"DMI_CPU0_PCH_TX_C_DN<3>";
32"DMI_CPU0_PCH_TX_C_DN<2>";
33"DMI_CPU0_PCH_TX_C_DN<1>";
34"DMI_CPU0_PCH_TX_C_DN<0>";
35"DMI_CPU0_PCH_TX_C_DP<3>";
36"DMI_CPU0_PCH_TX_C_DP<2>";
37"DMI_CPU0_PCH_TX_C_DP<1>";
38"DMI_CPU0_PCH_TX_C_DP<0>";
39"P3E_CPU0_PE1_PCH_C_TXP<10>";
40"P3E_CPU0_PE1_PCH_C_TXN<10>";
41"P3E_CPU0_PE1_PCH_C_TXN<11>";
42"P3E_CPU0_PE1_PCH_C_TXP<11>";
43"P3E_CPU0_PE1_PCH_C_TXP<12>";
44"P3E_CPU0_PE1_PCH_C_TXN<12>";
45"P3E_CPU0_PE1_PCH_C_TXP<13>";
46"P3E_CPU0_PE1_PCH_C_TXN<13>";
47"P3E_CPU0_PE1_PCH_C_TXP<14>";
48"P3E_CPU0_PE1_PCH_C_TXN<14>";
49"P3E_CPU0_PE1_PCH_C_TXP<15>";
50"P3E_CPU0_PE1_PCH_C_TXN<15>";
51"P3E_CPU0_PE1_PCH_C_TXP<9>";
52"P3E_CPU0_PE1_PCH_C_TXN<9>";
53"P3E_CPU0_PE1_PCH_RXN<0>";
54"P3E_CPU0_PE1_PCH_RXP<0>";
55"P3E_CPU0_PE1_PCH_RXN<1>";
56"P3E_CPU0_PE1_PCH_RXP<1>";
57"P3E_CPU0_PE1_PCH_RXN<2>";
58"P3E_CPU0_PE1_PCH_RXP<2>";
59"P3E_CPU0_PE1_PCH_RXN<3>";
60"P3E_CPU0_PE1_PCH_RXP<3>";
61"P3E_CPU0_PE1_PCH_RXN<4>";
62"P3E_CPU0_PE1_PCH_RXP<4>";
63"P3E_CPU0_PE1_PCH_RXN<5>";
64"P3E_CPU0_PE1_PCH_RXP<5>";
65"P3E_CPU0_PE1_PCH_RXN<6>";
66"P3E_CPU0_PE1_PCH_RXP<6>";
67"P3E_CPU0_PE1_PCH_RXN<7>";
68"P3E_CPU0_PE1_PCH_RXP<7>";
69"P3E_CPU0_PE1_PCH_R_RXN<8>";
70"P3E_CPU0_PE1_PCH_R_RXP<8>";
71"DMI_CPU0_PCH_RX_DN<3>";
72"DMI_CPU0_PCH_RX_DN<2>";
73"DMI_CPU0_PCH_RX_DN<1>";
74"DMI_CPU0_PCH_RX_DN<0>";
75"DMI_CPU0_PCH_RX_DP<3>";
76"DMI_CPU0_PCH_RX_DP<2>";
77"DMI_CPU0_PCH_RX_DP<1>";
78"DMI_CPU0_PCH_RX_DP<0>";
79"P3E_CPU0_PE1_PCH_R_RXN<10>";
80"P3E_CPU0_PE1_PCH_R_RXP<10>";
81"P3E_CPU0_PE1_PCH_R_RXN<11>";
82"P3E_CPU0_PE1_PCH_R_RXP<11>";
83"P3E_CPU0_PE1_PCH_R_RXN<12>";
84"P3E_CPU0_PE1_PCH_R_RXP<12>";
85"P3E_CPU0_PE1_PCH_R_RXN<13>";
86"P3E_CPU0_PE1_PCH_R_RXP<13>";
87"P3E_CPU0_PE1_PCH_R_RXN<14>";
88"P3E_CPU0_PE1_PCH_R_RXP<14>";
89"P3E_CPU0_PE1_PCH_R_RXN<15>";
90"P3E_CPU0_PE1_PCH_R_RXP<15>";
91"P3E_CPU0_PE1_PCH_R_RXN<9>";
92"P3E_CPU0_PE1_PCH_R_RXP<9>";
%"TAP"
"6","(-5500,2400)","0","mstr_standard","I101";
;
HDL_TAP"TRUE"
BODY_TYPE"PLUMBING"
CDS_LIB"mstr_standard";
"B \NAC \NWC"7;
"S \NAC"
BN"12"44;
%"TAP"
"6","(-5500,2500)","0","mstr_standard","I102";
;
HDL_TAP"TRUE"
BODY_TYPE"PLUMBING"
CDS_LIB"mstr_standard";
"B \NAC \NWC"7;
"S \NAC"
BN"13"46;
%"TAP"
"6","(-5500,2600)","0","mstr_standard","I103";
;
HDL_TAP"TRUE"
BODY_TYPE"PLUMBING"
CDS_LIB"mstr_standard";
"B \NAC \NWC"7;
"S \NAC"
BN"14"48;
%"TAP"
"6","(-5500,2700)","0","mstr_standard","I104";
;
HDL_TAP"TRUE"
BODY_TYPE"PLUMBING"
CDS_LIB"mstr_standard";
"B \NAC \NWC"7;
"S \NAC"
BN"15"50;
%"TAP"
"6","(-5625,1950)","0","mstr_standard","I105";
;
HDL_TAP"TRUE"
BODY_TYPE"PLUMBING"
CDS_LIB"mstr_standard";
"B \NAC \NWC"8;
"S \NAC"
BN"8"29;
%"TAP"
"6","(-5625,2050)","0","mstr_standard","I106";
;
HDL_TAP"TRUE"
BODY_TYPE"PLUMBING"
CDS_LIB"mstr_standard";
"B \NAC \NWC"8;
"S \NAC"
BN"9"51;
%"TAP"
"6","(-5625,2150)","0","mstr_standard","I107";
;
HDL_TAP"TRUE"
BODY_TYPE"PLUMBING"
CDS_LIB"mstr_standard";
"B \NAC \NWC"8;
"S \NAC"
BN"10"39;
%"TAP"
"6","(-5625,2350)","0","mstr_standard","I109";
;
HDL_TAP"TRUE"
BODY_TYPE"PLUMBING"
CDS_LIB"mstr_standard";
"B \NAC \NWC"8;
"S \NAC"
BN"12"43;
%"TAP"
"6","(-5625,2450)","0","mstr_standard","I110";
;
HDL_TAP"TRUE"
BODY_TYPE"PLUMBING"
CDS_LIB"mstr_standard";
"B \NAC \NWC"8;
"S \NAC"
BN"13"45;
%"TAP"
"6","(-5625,2550)","0","mstr_standard","I111";
;
HDL_TAP"TRUE"
BODY_TYPE"PLUMBING"
CDS_LIB"mstr_standard";
"B \NAC \NWC"8;
"S \NAC"
BN"14"47;
%"TAP"
"6","(-5625,2650)","0","mstr_standard","I112";
;
HDL_TAP"TRUE"
BODY_TYPE"PLUMBING"
CDS_LIB"mstr_standard";
"B \NAC \NWC"8;
"S \NAC"
BN"15"49;
%"TAP"
"1","(-2600,1950)","0","mstr_standard","I113";
;
HDL_TAP"TRUE"
BODY_TYPE"PLUMBING"
CDS_LIB"mstr_standard";
"B \NAC \NWC"2;
"S \NAC"
BN"8"69;
%"TAP"
"1","(-2600,2050)","0","mstr_standard","I114";
;
HDL_TAP"TRUE"
BODY_TYPE"PLUMBING"
CDS_LIB"mstr_standard";
"B \NAC \NWC"2;
"S \NAC"
BN"9"91;
%"TAP"
"1","(-2600,2150)","0","mstr_standard","I115";
;
HDL_TAP"TRUE"
BODY_TYPE"PLUMBING"
CDS_LIB"mstr_standard";
"B \NAC \NWC"2;
"S \NAC"
BN"10"79;
%"TAP"
"1","(-2600,2250)","0","mstr_standard","I116";
;
HDL_TAP"TRUE"
BODY_TYPE"PLUMBING"
CDS_LIB"mstr_standard";
"B \NAC \NWC"2;
"S \NAC"
BN"11"81;
%"TAP"
"1","(-2600,2350)","0","mstr_standard","I117";
;
HDL_TAP"TRUE"
BODY_TYPE"PLUMBING"
CDS_LIB"mstr_standard";
"B \NAC \NWC"2;
"S \NAC"
BN"12"83;
%"TAP"
"1","(-2600,2450)","0","mstr_standard","I118";
;
HDL_TAP"TRUE"
BODY_TYPE"PLUMBING"
CDS_LIB"mstr_standard";
"B \NAC \NWC"2;
"S \NAC"
BN"13"85;
%"TAP"
"1","(-2600,2550)","0","mstr_standard","I119";
;
HDL_TAP"TRUE"
BODY_TYPE"PLUMBING"
CDS_LIB"mstr_standard";
"B \NAC \NWC"2;
"S \NAC"
BN"14"87;
%"TAP"
"1","(-2600,2650)","0","mstr_standard","I120";
;
HDL_TAP"TRUE"
BODY_TYPE"PLUMBING"
CDS_LIB"mstr_standard";
"B \NAC \NWC"2;
"S \NAC"
BN"15"89;
%"TAP"
"1","(-2725,2000)","0","mstr_standard","I121";
;
HDL_TAP"TRUE"
BODY_TYPE"PLUMBING"
CDS_LIB"mstr_standard";
"B \NAC \NWC"1;
"S \NAC"
BN"8"70;
%"TAP"
"1","(-2725,2100)","0","mstr_standard","I122";
;
HDL_TAP"TRUE"
BODY_TYPE"PLUMBING"
CDS_LIB"mstr_standard";
"B \NAC \NWC"1;
"S \NAC"
BN"9"92;
%"TAP"
"1","(-2725,2200)","0","mstr_standard","I123";
;
HDL_TAP"TRUE"
BODY_TYPE"PLUMBING"
CDS_LIB"mstr_standard";
"B \NAC \NWC"1;
"S \NAC"
BN"10"80;
%"TAP"
"1","(-2725,2300)","0","mstr_standard","I124";
;
HDL_TAP"TRUE"
BODY_TYPE"PLUMBING"
CDS_LIB"mstr_standard";
"B \NAC \NWC"1;
"S \NAC"
BN"11"82;
%"TAP"
"1","(-2725,2400)","0","mstr_standard","I125";
;
HDL_TAP"TRUE"
BODY_TYPE"PLUMBING"
CDS_LIB"mstr_standard";
"B \NAC \NWC"1;
"S \NAC"
BN"12"84;
%"TAP"
"1","(-2725,2500)","0","mstr_standard","I126";
;
HDL_TAP"TRUE"
BODY_TYPE"PLUMBING"
CDS_LIB"mstr_standard";
"B \NAC \NWC"1;
"S \NAC"
BN"13"86;
%"TAP"
"1","(-2725,2600)","0","mstr_standard","I127";
;
HDL_TAP"TRUE"
BODY_TYPE"PLUMBING"
CDS_LIB"mstr_standard";
"B \NAC \NWC"1;
"S \NAC"
BN"14"88;
%"TAP"
"1","(-2725,2700)","0","mstr_standard","I128";
;
HDL_TAP"TRUE"
BODY_TYPE"PLUMBING"
CDS_LIB"mstr_standard";
"B \NAC \NWC"1;
"S \NAC"
BN"15"90;
%"TAP"
"6","(-5625,2300)","0","mstr_standard","I133";
;
HDL_TAP"TRUE"
BODY_TYPE"PLUMBING"
CDS_LIB"mstr_standard";
"B \NAC \NWC"8;
"S \NAC"
BN"11"42;
%"TAP"
"6","(-5500,2250)","0","mstr_standard","I134";
;
HDL_TAP"TRUE"
BODY_TYPE"PLUMBING"
CDS_LIB"mstr_standard";
"B \NAC \NWC"7;
"S \NAC"
BN"11"41;
%"TAP"
"1","(-5425,3150)","2","mstr_standard","I21";
;
HDL_TAP"TRUE"
BODY_TYPE"PLUMBING"
CDS_LIB"mstr_standard"
BOM_COST"SB";
"B \NAC \NWC"9;
"S \NAC"
BN"3"35;
%"TAP"
"1","(-5425,3050)","2","mstr_standard","I22";
;
HDL_TAP"TRUE"
BODY_TYPE"PLUMBING"
CDS_LIB"mstr_standard"
BOM_COST"SB";
"B \NAC \NWC"9;
"S \NAC"
BN"2"36;
%"TAP"
"1","(-5425,2950)","2","mstr_standard","I23";
;
HDL_TAP"TRUE"
BODY_TYPE"PLUMBING"
BOM_COST"SB"
CDS_LIB"mstr_standard";
"B \NAC \NWC"9;
"S \NAC"
BN"1"37;
%"TAP"
"1","(-5425,2850)","2","mstr_standard","I24";
;
HDL_TAP"TRUE"
BODY_TYPE"PLUMBING"
BOM_COST"SB"
CDS_LIB"mstr_standard";
"B \NAC \NWC"9;
"S \NAC"
BN"0"38;
%"TAP"
"1","(-5575,3100)","2","mstr_standard","I25";
;
HDL_TAP"TRUE"
BODY_TYPE"PLUMBING"
CDS_LIB"mstr_standard"
BOM_COST"SB";
"B \NAC \NWC"10;
"S \NAC"
BN"3"31;
%"TAP"
"1","(-5575,3000)","2","mstr_standard","I26";
;
HDL_TAP"TRUE"
BODY_TYPE"PLUMBING"
CDS_LIB"mstr_standard"
BOM_COST"SB";
"B \NAC \NWC"10;
"S \NAC"
BN"2"32;
%"TAP"
"1","(-5575,2900)","2","mstr_standard","I27";
;
HDL_TAP"TRUE"
BODY_TYPE"PLUMBING"
CDS_LIB"mstr_standard"
BOM_COST"SB";
"B \NAC \NWC"10;
"S \NAC"
BN"1"33;
%"TAP"
"1","(-5575,2800)","2","mstr_standard","I28";
;
HDL_TAP"TRUE"
BODY_TYPE"PLUMBING"
CDS_LIB"mstr_standard"
BOM_COST"SB";
"B \NAC \NWC"10;
"S \NAC"
BN"0"34;
%"TAP"
"6","(-2725,3150)","2","mstr_standard","I29";
;
HDL_TAP"TRUE"
BODY_TYPE"PLUMBING"
CDS_LIB"mstr_standard"
BOM_COST"SB";
"B \NAC \NWC"3;
"S \NAC"
BN"3"75;
%"TAP"
"6","(-2600,3100)","2","mstr_standard","I30";
;
HDL_TAP"TRUE"
BODY_TYPE"PLUMBING"
CDS_LIB"mstr_standard"
BOM_COST"SB";
"B \NAC \NWC"4;
"S \NAC"
BN"3"71;
%"TAP"
"6","(-2725,3050)","2","mstr_standard","I31";
;
HDL_TAP"TRUE"
BODY_TYPE"PLUMBING"
CDS_LIB"mstr_standard"
BOM_COST"SB";
"B \NAC \NWC"3;
"S \NAC"
BN"2"76;
%"TAP"
"6","(-2725,2950)","2","mstr_standard","I32";
;
HDL_TAP"TRUE"
BODY_TYPE"PLUMBING"
CDS_LIB"mstr_standard"
BOM_COST"SB";
"B \NAC \NWC"3;
"S \NAC"
BN"1"77;
%"TAP"
"6","(-2725,2850)","2","mstr_standard","I33";
;
HDL_TAP"TRUE"
BODY_TYPE"PLUMBING"
BOM_COST"SB"
CDS_LIB"mstr_standard";
"B \NAC \NWC"3;
"S \NAC"
BN"0"78;
%"TAP"
"6","(-2600,3000)","2","mstr_standard","I34";
;
HDL_TAP"TRUE"
BODY_TYPE"PLUMBING"
CDS_LIB"mstr_standard"
BOM_COST"SB";
"B \NAC \NWC"4;
"S \NAC"
BN"2"72;
%"TAP"
"6","(-2600,2900)","2","mstr_standard","I35";
;
HDL_TAP"TRUE"
BODY_TYPE"PLUMBING"
CDS_LIB"mstr_standard"
BOM_COST"SB";
"B \NAC \NWC"4;
"S \NAC"
BN"1"73;
%"TAP"
"6","(-2600,2800)","2","mstr_standard","I36";
;
HDL_TAP"TRUE"
BODY_TYPE"PLUMBING"
BOM_COST"SB"
CDS_LIB"mstr_standard";
"B \NAC \NWC"4;
"S \NAC"
BN"0"74;
%"TAP"
"6","(-5625,1150)","0","mstr_standard","I42";
;
HDL_TAP"TRUE"
BODY_TYPE"PLUMBING"
CDS_LIB"mstr_standard";
"B \NAC \NWC"12;
"S \NAC"
BN"0"13;
%"TAP"
"6","(-5625,1250)","0","mstr_standard","I43";
;
HDL_TAP"TRUE"
BODY_TYPE"PLUMBING"
CDS_LIB"mstr_standard";
"B \NAC \NWC"12;
"S \NAC"
BN"1"15;
%"TAP"
"6","(-5625,1450)","0","mstr_standard","I44";
;
HDL_TAP"TRUE"
BODY_TYPE"PLUMBING"
CDS_LIB"mstr_standard";
"B \NAC \NWC"12;
"S \NAC"
BN"3"19;
%"TAP"
"6","(-5625,1350)","0","mstr_standard","I45";
;
HDL_TAP"TRUE"
BODY_TYPE"PLUMBING"
CDS_LIB"mstr_standard";
"B \NAC \NWC"12;
"S \NAC"
BN"2"17;
%"TAP"
"6","(-5625,1550)","0","mstr_standard","I46";
;
HDL_TAP"TRUE"
BODY_TYPE"PLUMBING"
CDS_LIB"mstr_standard";
"B \NAC \NWC"12;
"S \NAC"
BN"4"21;
%"TAP"
"6","(-5625,1650)","0","mstr_standard","I47";
;
HDL_TAP"TRUE"
BODY_TYPE"PLUMBING"
CDS_LIB"mstr_standard";
"B \NAC \NWC"12;
"S \NAC"
BN"5"23;
%"TAP"
"6","(-5625,1750)","0","mstr_standard","I48";
;
HDL_TAP"TRUE"
BODY_TYPE"PLUMBING"
CDS_LIB"mstr_standard";
"B \NAC \NWC"12;
"S \NAC"
BN"6"25;
%"TAP"
"6","(-5625,1850)","0","mstr_standard","I50";
;
HDL_TAP"TRUE"
BODY_TYPE"PLUMBING"
CDS_LIB"mstr_standard";
"B \NAC \NWC"12;
"S \NAC"
BN"7"27;
%"TAP"
"6","(-5500,1200)","0","mstr_standard","I58";
;
HDL_TAP"TRUE"
BODY_TYPE"PLUMBING"
CDS_LIB"mstr_standard";
"B \NAC \NWC"11;
"S \NAC"
BN"0"14;
%"TAP"
"6","(-5500,1300)","0","mstr_standard","I59";
;
HDL_TAP"TRUE"
BODY_TYPE"PLUMBING"
CDS_LIB"mstr_standard";
"B \NAC \NWC"11;
"S \NAC"
BN"1"16;
%"TAP"
"6","(-5500,1400)","0","mstr_standard","I60";
;
HDL_TAP"TRUE"
BODY_TYPE"PLUMBING"
CDS_LIB"mstr_standard";
"B \NAC \NWC"11;
"S \NAC"
BN"2"18;
%"TAP"
"6","(-5500,1500)","0","mstr_standard","I61";
;
HDL_TAP"TRUE"
BODY_TYPE"PLUMBING"
CDS_LIB"mstr_standard";
"B \NAC \NWC"11;
"S \NAC"
BN"3"20;
%"TAP"
"6","(-5500,1700)","0","mstr_standard","I62";
;
HDL_TAP"TRUE"
BODY_TYPE"PLUMBING"
CDS_LIB"mstr_standard";
"B \NAC \NWC"11;
"S \NAC"
BN"5"24;
%"TAP"
"6","(-5500,1600)","0","mstr_standard","I63";
;
HDL_TAP"TRUE"
BODY_TYPE"PLUMBING"
CDS_LIB"mstr_standard";
"B \NAC \NWC"11;
"S \NAC"
BN"4"22;
%"TAP"
"6","(-5500,1800)","0","mstr_standard","I64";
;
HDL_TAP"TRUE"
BODY_TYPE"PLUMBING"
CDS_LIB"mstr_standard";
"B \NAC \NWC"11;
"S \NAC"
BN"6"26;
%"TAP"
"6","(-5500,1900)","0","mstr_standard","I65";
;
HDL_TAP"TRUE"
BODY_TYPE"PLUMBING"
CDS_LIB"mstr_standard";
"B \NAC \NWC"11;
"S \NAC"
BN"7"28;
%"TAP"
"1","(-2725,1200)","0","mstr_standard","I74";
;
HDL_TAP"TRUE"
BODY_TYPE"PLUMBING"
CDS_LIB"mstr_standard";
"B \NAC \NWC"5;
"S \NAC"
BN"0"54;
%"TAP"
"1","(-2725,1300)","0","mstr_standard","I75";
;
HDL_TAP"TRUE"
BODY_TYPE"PLUMBING"
CDS_LIB"mstr_standard";
"B \NAC \NWC"5;
"S \NAC"
BN"1"56;
%"TAP"
"1","(-2725,1400)","0","mstr_standard","I76";
;
HDL_TAP"TRUE"
BODY_TYPE"PLUMBING"
CDS_LIB"mstr_standard";
"B \NAC \NWC"5;
"S \NAC"
BN"2"58;
%"TAP"
"1","(-2725,1500)","0","mstr_standard","I77";
;
HDL_TAP"TRUE"
BODY_TYPE"PLUMBING"
CDS_LIB"mstr_standard";
"B \NAC \NWC"5;
"S \NAC"
BN"3"60;
%"TAP"
"1","(-2725,1600)","0","mstr_standard","I78";
;
HDL_TAP"TRUE"
BODY_TYPE"PLUMBING"
CDS_LIB"mstr_standard";
"B \NAC \NWC"5;
"S \NAC"
BN"4"62;
%"TAP"
"1","(-2600,1250)","0","mstr_standard","I79";
;
HDL_TAP"TRUE"
BODY_TYPE"PLUMBING"
CDS_LIB"mstr_standard";
"B \NAC \NWC"6;
"S \NAC"
BN"1"55;
%"TAP"
"1","(-2600,1150)","0","mstr_standard","I80";
;
HDL_TAP"TRUE"
BODY_TYPE"PLUMBING"
CDS_LIB"mstr_standard";
"B \NAC \NWC"6;
"S \NAC"
BN"0"53;
%"TAP"
"1","(-2600,1350)","0","mstr_standard","I81";
;
HDL_TAP"TRUE"
BODY_TYPE"PLUMBING"
CDS_LIB"mstr_standard";
"B \NAC \NWC"6;
"S \NAC"
BN"2"57;
%"TAP"
"1","(-2600,1450)","0","mstr_standard","I82";
;
HDL_TAP"TRUE"
BODY_TYPE"PLUMBING"
CDS_LIB"mstr_standard";
"B \NAC \NWC"6;
"S \NAC"
BN"3"59;
%"TAP"
"1","(-2600,1650)","0","mstr_standard","I83";
;
HDL_TAP"TRUE"
BODY_TYPE"PLUMBING"
CDS_LIB"mstr_standard";
"B \NAC \NWC"6;
"S \NAC"
BN"5"63;
%"TAP"
"1","(-2600,1550)","0","mstr_standard","I84";
;
HDL_TAP"TRUE"
BODY_TYPE"PLUMBING"
CDS_LIB"mstr_standard";
"B \NAC \NWC"6;
"S \NAC"
BN"4"61;
%"TAP"
"1","(-2725,1700)","0","mstr_standard","I85";
;
HDL_TAP"TRUE"
BODY_TYPE"PLUMBING"
CDS_LIB"mstr_standard";
"B \NAC \NWC"5;
"S \NAC"
BN"5"64;
%"TAP"
"1","(-2725,1800)","0","mstr_standard","I86";
;
HDL_TAP"TRUE"
BODY_TYPE"PLUMBING"
CDS_LIB"mstr_standard";
"B \NAC \NWC"5;
"S \NAC"
BN"6"66;
%"TAP"
"1","(-2725,1900)","0","mstr_standard","I87";
;
HDL_TAP"TRUE"
BODY_TYPE"PLUMBING"
CDS_LIB"mstr_standard";
"B \NAC \NWC"5;
"S \NAC"
BN"7"68;
%"LBG_CORE_QAT_EXT_D"
"4","(-3925,2150)","0","mstr_u_proc","I9";
;
CDS_SEC"4"
ROOM"SB"
CDS_LOCATION"U7C1"
BOM_COST"SB"
CDS_LIB"mstr_u_proc"
SEC"4"
SEC_TYPE"BGA1"
PACK_TYPE"BGA1"
MATERIAL"IC"
PART_NUMBER"H91415-002"
LOCATION"U7C1";
"PCIEUP_9_TXP"
$PN"M66"92;
"PCIEUP_9_TXN"
$PN"J66"91;
"PCIEUP_9_RXP"
$PN"B58"52;
"PCIEUP_9_RXN"
$PN"D58"51;
"PCIEUP_8_TXP"
$PN"M63"70;
"PCIEUP_8_TXN"
$PN"K65"69;
"PCIEUP_8_RXP"
$PN"A57"30;
"PCIEUP_8_RXN"
$PN"C57"29;
"PCIEUP_7_TXP"
$PN"R61"68;
"PCIEUP_7_TXN"
$PN"P59"67;
"PCIEUP_7_RXP"
$PN"B55"28;
"PCIEUP_7_RXN"
$PN"D55"27;
"PCIEUP_6_TXP"
$PN"J63"66;
"PCIEUP_6_TXN"
$PN"H61"65;
"PCIEUP_6_RXP"
$PN"A54"26;
"PCIEUP_6_RXN"
$PN"C54"25;
"PCIEUP_5_TXP"
$PN"K61"64;
"PCIEUP_5_TXN"
$PN"N61"63;
"PCIEUP_5_RXP"
$PN"B53"24;
"PCIEUP_5_RXN"
$PN"D53"23;
"PCIEUP_4_TXP"
$PN"M59"62;
"PCIEUP_4_TXN"
$PN"N58"61;
"PCIEUP_4_RXP"
$PN"A52"22;
"PCIEUP_4_RXN"
$PN"C52"21;
"PCIEUP_3_TXP"
$PN"K58"60;
"PCIEUP_3_TXN"
$PN"J56"59;
"PCIEUP_3_RXP"
$PN"B51"20;
"PCIEUP_3_RXN"
$PN"D51"19;
"PCIEUP_2_TXP"
$PN"G56"58;
"PCIEUP_2_TXN"
$PN"H54"57;
"PCIEUP_2_RXP"
$PN"A50"18;
"PCIEUP_2_RXN"
$PN"C50"17;
"PCIEUP_1_TXP"
$PN"M56"56;
"PCIEUP_1_TXN"
$PN"P56"55;
"PCIEUP_1_RXP"
$PN"B49"16;
"PCIEUP_1_RXN"
$PN"D49"15;
"PCIEUP_15_TXP"
$PN"AA65"90;
"PCIEUP_15_TXN"
$PN"Y66"89;
"PCIEUP_15_RXP"
$PN"B64"50;
"PCIEUP_15_RXN"
$PN"D64"49;
"PCIEUP_14_TXP"
$PN"V63"88;
"PCIEUP_14_TXN"
$PN"W65"87;
"PCIEUP_14_RXP"
$PN"A63"48;
"PCIEUP_14_RXN"
$PN"C63"47;
"PCIEUP_13_TXP"
$PN"U61"86;
"PCIEUP_13_TXN"
$PN"T63"85;
"PCIEUP_13_RXP"
$PN"B62"46;
"PCIEUP_13_RXN"
$PN"D62"45;
"PCIEUP_12_TXP"
$PN"U65"84;
"PCIEUP_12_TXN"
$PN"R65"83;
"PCIEUP_12_RXP"
$PN"A61"44;
"PCIEUP_12_RXN"
$PN"C61"43;
"PCIEUP_11_TXP"
$PN"V59"82;
"PCIEUP_11_TXN"
$PN"T59"81;
"PCIEUP_11_RXP"
$PN"B60"42;
"PCIEUP_11_RXN"
$PN"D60"41;
"PCIEUP_10_TXP"
$PN"P66"80;
"PCIEUP_10_TXN"
$PN"N65"79;
"PCIEUP_10_RXP"
$PN"A59"40;
"PCIEUP_10_RXN"
$PN"C59"39;
"PCIEUP_0_TXP"
$PN"G52"54;
"PCIEUP_0_TXN"
$PN"J52"53;
"PCIEUP_0_RXP"
$PN"A48"14;
"PCIEUP_0_RXN"
$PN"C48"13;
"DMI_TXP<0>"
$PN"K46"78;
"DMI_TXP<1>"
$PN"H50"77;
"DMI_TXP<2>"
$PN"M52"76;
"DMI_TXP<3>"
$PN"N54"75;
"DMI_TXN<0>"
$PN"H46"74;
"DMI_TXN<1>"
$PN"J48"73;
"DMI_TXN<2>"
$PN"K50"72;
"DMI_TXN<3>"
$PN"P52"71;
"DMI_RXP<0>"
$PN"B42"38;
"DMI_RXP<1>"
$PN"A43"37;
"DMI_RXP<2>"
$PN"B44"36;
"DMI_RXP<3>"
$PN"A45"35;
"DMI_RXN<0>"
$PN"D42"34;
"DMI_RXN<1>"
$PN"C43"33;
"DMI_RXN<2>"
$PN"D44"32;
"DMI_RXN<3>"
$PN"C45"31;
%"TAP"
"1","(-2600,1750)","0","mstr_standard","I90";
;
HDL_TAP"TRUE"
BODY_TYPE"PLUMBING"
CDS_LIB"mstr_standard";
"B \NAC \NWC"6;
"S \NAC"
BN"6"65;
%"TAP"
"1","(-2600,1850)","0","mstr_standard","I91";
;
HDL_TAP"TRUE"
BODY_TYPE"PLUMBING"
CDS_LIB"mstr_standard";
"B \NAC \NWC"6;
"S \NAC"
BN"7"67;
%"TAP"
"6","(-5500,2000)","0","mstr_standard","I97";
;
HDL_TAP"TRUE"
BODY_TYPE"PLUMBING"
CDS_LIB"mstr_standard";
"B \NAC \NWC"7;
"S \NAC"
BN"8"30;
%"TAP"
"6","(-5500,2100)","0","mstr_standard","I98";
;
HDL_TAP"TRUE"
BODY_TYPE"PLUMBING"
CDS_LIB"mstr_standard";
"B \NAC \NWC"7;
"S \NAC"
BN"9"52;
%"TAP"
"6","(-5500,2200)","0","mstr_standard","I99";
;
HDL_TAP"TRUE"
BODY_TYPE"PLUMBING"
CDS_LIB"mstr_standard";
"B \NAC \NWC"7;
"S \NAC"
BN"10"40;
END.
